# BASEBOARD_FAB2 (Tioga Pass) — schematic netlist excerpt (pin names and nets, part order shuffled) for the footprints in the layout excerpt that follows; sources: Cadence DE-HDL packaged netlist, KiCad conversion of Wiwynn_Tioga_Pass_MB.brd

EU1D2  ADM1278  IC  pkg SM  page 199
  PSET  = A_HSC_PSET
  VCAP  = A_HSC_VCAP
  ISET  = A_HSC_ISET
  ISTART  = A_HSC_ISTART
  TIMER  = A_HSC_TIMER
  FAULT_N  = IRQ_HSC_FAULT_R_N
  ADR1  = FM_P12V_HSC_ADR1
  ADR2  = FM_P12V_HSC_ADR2
  SPISS_N  = TP_HSC_SPISSN
  MCLK  = TP_HSC_MCLK
  MDAT  = TP_HSC_MDAT
  ENABLE  = FM_P12V_HOTSWAP0_EN
  GPO1_ALERT1_N_CONV  = IRQ_SML1_PMBUS_ALERT_R_N
  GPO2_ALERT2_N  = TP_HSC_ALERT2_N
  SDA  = SMB_3V3SB_HSC_SDA_R
  SCL  = SMB_3V3SB_HSC_SCL_R
  RETRY_N  = PD_HSC_RETRY_N
  PWRGD  = PWRGD_P12V_R
  CSOUT  = A_HSC_CSOUT
  VOUT  = A_HSC_VOUT
  PWGIN  = A_HSC_PWGIN
  GND  = AGND_HSC
  PGND  = GND
  GATE  = A_HSC_GATE
  TEMP  = A_HSC_TEMP
  MON  = A_HSC_MON
  HSN  = A_HSC_HSN
  HSP  = A_HSC_HSP
  MOP  = A_HSC_MOP
  VCC  = P12V_HSC_VCC
  UV  = A_HSC_UV
  OV  = A_HSC_OV
  EP  = AGND_HSC

(kicad_pcb
	(version 20260206)
	(generator "pcbnew")
	(generator_version "10.0")
	(general
		(thickness 1.6)
		(legacy_teardrops no)
	)
	(paper "A4")
	(title_block
		(title "Wiwynn_Tioga_Pass_MB.brd")
		(comment 1 "Tioga Pass / footprint 2252 of 4770 (EU1D2), pads 18-33 of 33")
	)
	(layers
		(0 "F.Cu" signal "TOP")
		(4 "In1.Cu" signal "L2GND")
		(6 "In2.Cu" signal "L3")
		(8 "In3.Cu" signal "L4GND")
		(10 "In4.Cu" signal "L5")
		(12 "In5.Cu" signal "L6GND")
		(14 "In6.Cu" signal "L7VCC")
		(16 "In7.Cu" signal "L8VCC")
		(18 "In8.Cu" signal "L9GND")
		(20 "In9.Cu" signal "L10")
		(22 "In10.Cu" signal "L11GND")
		(24 "In11.Cu" signal "L12")
		(26 "In12.Cu" signal "L13GND")
		(2 "B.Cu" signal "BOTTOM")
		(9 "F.Adhes" user "F.Adhesive")
		(11 "B.Adhes" user "B.Adhesive")
		(13 "F.Paste" user "Package Geometry/Pastemask Top")
		(15 "B.Paste" user "Package Geometry/Pastemask Bottom")
		(5 "F.SilkS" user "Ref Des/Silkscreen Top")
		(7 "B.SilkS" user "Ref Des/Silkscreen Bottom")
		(1 "F.Mask" user "Board Geometry/Soldermask Top")
		(3 "B.Mask" user "Board Geometry/Soldermask Bottom")
		(17 "Dwgs.User" user "User.Drawings")
		(19 "Cmts.User" user "User.Comments")
		(21 "Eco1.User" user "User.Eco1")
		(23 "Eco2.User" user "User.Eco2")
		(25 "Edge.Cuts" user "Board Geometry/Outline")
		(27 "Margin" user)
		(31 "F.CrtYd" user "Package Geometry/Place Bound Top")
		(29 "B.CrtYd" user "Package Geometry/Place Bound Bottom")
		(35 "F.Fab" user "Ref Des/Assembly Top")
		(33 "B.Fab" user "Ref Des/Assembly Bottom")
	)
	(footprint ""
		(layer "F.Cu")
		(at 18.161 -75.692 180)
		(property "Reference" "EU1D2"
			(at -0.127 -3.58267 0)
			(unlocked yes)
			(layer "F.SilkS")
			(effects
				(font
					(size 0.7874 0.5842)
					(thickness 0.1524)
				)
			)
		)
		(property "Value" ""
			(at 0 0 180)
			(layer "F.Fab")
			(effects
				(font
					(size 1.27 1.27)
				)
			)
		)
		(duplicate_pad_numbers_are_jumpers no)
		(pad "18" smd custom
			(at 2.3495 1.25095 180)
			(size 0.0762 0.0762)
			(layers "F.Cu" "F.Mask" "F.Paste")
			(net "PWRGD_P12V_R")
			(options
				(clearance outline)
				(anchor circle)
			)
			(primitives
				(gr_poly
					(pts
						(xy 0.3556 -0.1524) (xy 0.3556 0.1524)
						(arc
							(start -0.2032 0.1524)
							(mid -0.3556 0)
							(end -0.2032 -0.1524)
						)
					)
					(width 0)
					(fill yes)
				)
			)
		)
		(pad "19" smd custom
			(at 2.3495 0.75057 180)
			(size 0.0762 0.0762)
			(layers "F.Cu" "F.Mask" "F.Paste")
			(net "A_HSC_CSOUT")
			(options
				(clearance outline)
				(anchor circle)
			)
			(primitives
				(gr_poly
					(pts
						(xy 0.3556 -0.1524) (xy 0.3556 0.1524)
						(arc
							(start -0.2032 0.1524)
							(mid -0.3556 0)
							(end -0.2032 -0.1524)
						)
					)
					(width 0)
					(fill yes)
				)
			)
		)
		(pad "20" smd custom
			(at 2.3495 0.25019 180)
			(size 0.0762 0.0762)
			(layers "F.Cu" "F.Mask" "F.Paste")
			(net "A_HSC_VOUT")
			(options
				(clearance outline)
				(anchor circle)
			)
			(primitives
				(gr_poly
					(pts
						(xy 0.3556 -0.1524) (xy 0.3556 0.1524)
						(arc
							(start -0.2032 0.1524)
							(mid -0.3556 0)
							(end -0.2032 -0.1524)
						)
					)
					(width 0)
					(fill yes)
				)
			)
		)
		(pad "21" smd custom
			(at 2.3495 -0.25019 180)
			(size 0.0762 0.0762)
			(layers "F.Cu" "F.Mask" "F.Paste")
			(net "A_HSC_PWGIN")
			(options
				(clearance outline)
				(anchor circle)
			)
			(primitives
				(gr_poly
					(pts
						(xy 0.3556 -0.1524) (xy 0.3556 0.1524)
						(arc
							(start -0.2032 0.1524)
							(mid -0.3556 0)
							(end -0.2032 -0.1524)
						)
					)
					(width 0)
					(fill yes)
				)
			)
		)
		(pad "22" smd custom
			(at 2.3495 -0.75057 180)
			(size 0.0762 0.0762)
			(layers "F.Cu" "F.Mask" "F.Paste")
			(net "AGND_HSC")
			(options
				(clearance outline)
				(anchor circle)
			)
			(primitives
				(gr_poly
					(pts
						(xy 0.3556 -0.1524) (xy 0.3556 0.1524)
						(arc
							(start -0.2032 0.1524)
							(mid -0.3556 0)
							(end -0.2032 -0.1524)
						)
					)
					(width 0)
					(fill yes)
				)
			)
		)
		(pad "23" smd custom
			(at 2.3495 -1.25095 180)
			(size 0.0762 0.0762)
			(layers "F.Cu" "F.Mask" "F.Paste")
			(net "GND")
			(options
				(clearance outline)
				(anchor circle)
			)
			(primitives
				(gr_poly
					(pts
						(xy 0.3556 -0.1524) (xy 0.3556 0.1524)
						(arc
							(start -0.2032 0.1524)
							(mid -0.3556 0)
							(end -0.2032 -0.1524)
						)
					)
					(width 0)
					(fill yes)
				)
			)
		)
		(pad "24" smd custom
			(at 2.3495 -1.75133 180)
			(size 0.0762 0.0762)
			(layers "F.Cu" "F.Mask" "F.Paste")
			(net "A_HSC_GATE")
			(options
				(clearance outline)
				(anchor circle)
			)
			(primitives
				(gr_poly
					(pts
						(xy 0.3556 -0.1524) (xy 0.3556 0.1524)
						(arc
							(start -0.2032 0.1524)
							(mid -0.3556 0)
							(end -0.2032 -0.1524)
						)
					)
					(width 0)
					(fill yes)
				)
			)
		)
		(pad "25" smd custom
			(at 1.75133 -2.3495 180)
			(size 0.0762 0.0762)
			(layers "F.Cu" "F.Mask" "F.Paste")
			(net "A_HSC_TEMP")
			(options
				(clearance outline)
				(anchor circle)
			)
			(primitives
				(gr_poly
					(pts
						(xy -0.1524 -0.3556) (xy 0.1524 -0.3556)
						(arc
							(start 0.1524 0.2032)
							(mid 0 0.3556)
							(end -0.1524 0.2032)
						)
					)
					(width 0)
					(fill yes)
				)
			)
		)
		(pad "26" smd custom
			(at 1.25095 -2.3495 180)
			(size 0.0762 0.0762)
			(layers "F.Cu" "F.Mask" "F.Paste")
			(net "A_HSC_MON")
			(options
				(clearance outline)
				(anchor circle)
			)
			(primitives
				(gr_poly
					(pts
						(xy -0.1524 -0.3556) (xy 0.1524 -0.3556)
						(arc
							(start 0.1524 0.2032)
							(mid 0 0.3556)
							(end -0.1524 0.2032)
						)
					)
					(width 0)
					(fill yes)
				)
			)
		)
		(pad "27" smd custom
			(at 0.75057 -2.3495 180)
			(size 0.0762 0.0762)
			(layers "F.Cu" "F.Mask" "F.Paste")
			(net "A_HSC_HSN")
			(options
				(clearance outline)
				(anchor circle)
			)
			(primitives
				(gr_poly
					(pts
						(xy -0.1524 -0.3556) (xy 0.1524 -0.3556)
						(arc
							(start 0.1524 0.2032)
							(mid 0 0.3556)
							(end -0.1524 0.2032)
						)
					)
					(width 0)
					(fill yes)
				)
			)
		)
		(pad "28" smd custom
			(at 0.25019 -2.3495 180)
			(size 0.0762 0.0762)
			(layers "F.Cu" "F.Mask" "F.Paste")
			(net "A_HSC_HSP")
			(options
				(clearance outline)
				(anchor circle)
			)
			(primitives
				(gr_poly
					(pts
						(xy -0.1524 -0.3556) (xy 0.1524 -0.3556)
						(arc
							(start 0.1524 0.2032)
							(mid 0 0.3556)
							(end -0.1524 0.2032)
						)
					)
					(width 0)
					(fill yes)
				)
			)
		)
		(pad "29" smd custom
			(at -0.25019 -2.3495 180)
			(size 0.0762 0.0762)
			(layers "F.Cu" "F.Mask" "F.Paste")
			(net "A_HSC_MOP")
			(options
				(clearance outline)
				(anchor circle)
			)
			(primitives
				(gr_poly
					(pts
						(xy -0.1524 -0.3556) (xy 0.1524 -0.3556)
						(arc
							(start 0.1524 0.2032)
							(mid 0 0.3556)
							(end -0.1524 0.2032)
						)
					)
					(width 0)
					(fill yes)
				)
			)
		)
		(pad "30" smd custom
			(at -0.75057 -2.3495 180)
			(size 0.0762 0.0762)
			(layers "F.Cu" "F.Mask" "F.Paste")
			(net "P12V_HSC_VCC")
			(options
				(clearance outline)
				(anchor circle)
			)
			(primitives
				(gr_poly
					(pts
						(xy -0.1524 -0.3556) (xy 0.1524 -0.3556)
						(arc
							(start 0.1524 0.2032)
							(mid 0 0.3556)
							(end -0.1524 0.2032)
						)
					)
					(width 0)
					(fill yes)
				)
			)
		)
		(pad "31" smd custom
			(at -1.25095 -2.3495 180)
			(size 0.0762 0.0762)
			(layers "F.Cu" "F.Mask" "F.Paste")
			(net "A_HSC_UV")
			(options
				(clearance outline)
				(anchor circle)
			)
			(primitives
				(gr_poly
					(pts
						(xy -0.1524 -0.3556) (xy 0.1524 -0.3556)
						(arc
							(start 0.1524 0.2032)
							(mid 0 0.3556)
							(end -0.1524 0.2032)
						)
					)
					(width 0)
					(fill yes)
				)
			)
		)
		(pad "32" smd custom
			(at -1.75133 -2.3495 180)
			(size 0.0762 0.0762)
			(layers "F.Cu" "F.Mask" "F.Paste")
			(net "A_HSC_OV")
			(options
				(clearance outline)
				(anchor circle)
			)
			(primitives
				(gr_poly
					(pts
						(xy -0.1524 -0.3556) (xy 0.1524 -0.3556)
						(arc
							(start 0.1524 0.2032)
							(mid 0 0.3556)
							(end -0.1524 0.2032)
						)
					)
					(width 0)
					(fill yes)
				)
			)
		)
		(pad "33" smd rect
			(at 0 0 180)
			(size 3.302 3.302)
			(layers "F.Cu" "F.Mask" "F.Paste")
			(net "AGND_HSC")
		)
	)
)
